# T6G (Grand Teton) — schematic netlist excerpt (pin names and nets, part order shuffled) for the footprints in the layout excerpt that follows; sources: Cadence DE-HDL packaged netlist, KiCad conversion of 04192023_DAF0TMB3IC0_F0TG_MB_C_brd_V02_OCP.brd

PC6641  Q_CAP  560PF 50V 10% EMPTY  pkg C0402  page 365 : A = SW_P0V9_RETIMER_CPU1_SW2 ; B = SW_P0V9_RETIMER_CPU1_SW2_RC
R3758  Q_RES  10 1% CHIP  pkg 0402LF  page 236 : A = P3V3_E1S_0_R ; B = VSENSE_P3V3_INA230_2_INP

(kicad_pcb
	(version 20260206)
	(generator "pcbnew")
	(generator_version "10.0")
	(general
		(thickness 1.6)
		(legacy_teardrops no)
	)
	(paper "A4")
	(title_block
		(title "04192023_DAF0TMB3IC0_F0TG_MB_C_brd_V02_OCP.brd")
		(comment 1 "Grand Teton / footprints 2194-2195 of 8354")
	)
	(layers
		(0 "F.Cu" signal "TOP")
		(4 "In1.Cu" signal "GND")
		(6 "In2.Cu" signal "IN1")
		(8 "In3.Cu" signal "GND1")
		(10 "In4.Cu" signal "IN2")
		(12 "In5.Cu" signal "GND2")
		(14 "In6.Cu" signal "IN3")
		(16 "In7.Cu" signal "GND3")
		(18 "In8.Cu" signal "VCC")
		(20 "In9.Cu" signal "VCC1")
		(22 "In10.Cu" signal "GND4")
		(24 "In11.Cu" signal "IN4")
		(26 "In12.Cu" signal "GND5")
		(28 "In13.Cu" signal "IN5")
		(30 "In14.Cu" signal "GND6")
		(32 "In15.Cu" signal "IN6")
		(34 "In16.Cu" signal "GND7")
		(2 "B.Cu" signal "BOTTOM")
		(9 "F.Adhes" user "F.Adhesive")
		(11 "B.Adhes" user "B.Adhesive")
		(13 "F.Paste" user "Package Geometry/Pastemask Top")
		(15 "B.Paste" user "Package Geometry/Pastemask Bottom")
		(5 "F.SilkS" user "Ref Des/Silkscreen Top")
		(7 "B.SilkS" user "Ref Des/Silkscreen Bottom")
		(1 "F.Mask" user "Board Geometry/Soldermask Top")
		(3 "B.Mask" user "Board Geometry/Soldermask Bottom")
		(17 "Dwgs.User" user "User.Drawings")
		(19 "Cmts.User" user "User.Comments")
		(21 "Eco1.User" user "User.Eco1")
		(23 "Eco2.User" user "User.Eco2")
		(25 "Edge.Cuts" user "Board Geometry/Outline")
		(27 "Margin" user)
		(31 "F.CrtYd" user "Package Geometry/Place Bound Top")
		(29 "B.CrtYd" user "Package Geometry/Place Bound Bottom")
		(35 "F.Fab" user "Ref Des/Assembly Top")
		(33 "B.Fab" user "Ref Des/Assembly Bottom")
	)
	(footprint ""
		(layer "F.Cu")
		(at 220.190822 -57.851802 180)
		(property "Reference" "R3758"
			(at 0 0 180)
			(layer "F.SilkS")
			(hide yes)
			(effects
				(font
					(size 1.27 1.27)
				)
			)
		)
		(property "Value" ""
			(at 0 0 180)
			(layer "F.Fab")
			(effects
				(font
					(size 1.27 1.27)
				)
			)
		)
		(duplicate_pad_numbers_are_jumpers no)
		(fp_line
			(start 0.7874 0.4064)
			(end -0.7874 0.4064)
			(stroke
				(width 0.1524)
				(type default)
			)
			(layer "F.SilkS")
		)
		(fp_line
			(start 0.7874 -0.4064)
			(end 0.7874 0.4064)
			(stroke
				(width 0.1524)
				(type default)
			)
			(layer "F.SilkS")
		)
		(fp_line
			(start -0.7874 0.4064)
			(end -0.7874 -0.4064)
			(stroke
				(width 0.1524)
				(type default)
			)
			(layer "F.SilkS")
		)
		(fp_line
			(start -0.7874 -0.4064)
			(end 0.7874 -0.4064)
			(stroke
				(width 0.1524)
				(type default)
			)
			(layer "F.SilkS")
		)
		(fp_line
			(start 0.67945 0.3048)
			(end 0.120396 0.3048)
			(stroke
				(width 0.1)
				(type default)
			)
			(layer "F.Fab")
		)
		(fp_line
			(start 0.67945 -0.3048)
			(end 0.67945 0.3048)
			(stroke
				(width 0.1)
				(type default)
			)
			(layer "F.Fab")
		)
		(fp_line
			(start 0.12065 -0.2794)
			(end 0.12065 -0.3048)
			(stroke
				(width 0.1)
				(type default)
			)
			(layer "F.Fab")
		)
		(fp_line
			(start 0.12065 -0.3048)
			(end 0.67945 -0.3048)
			(stroke
				(width 0.1)
				(type default)
			)
			(layer "F.Fab")
		)
		(fp_line
			(start 0.120396 0.3048)
			(end 0.120396 0.2794)
			(stroke
				(width 0.1)
				(type default)
			)
			(layer "F.Fab")
		)
		(fp_line
			(start 0.120396 0.2794)
			(end -0.12065 0.2794)
			(stroke
				(width 0.1)
				(type default)
			)
			(layer "F.Fab")
		)
		(fp_line
			(start -0.12065 0.3048)
			(end -0.67945 0.3048)
			(stroke
				(width 0.1)
				(type default)
			)
			(layer "F.Fab")
		)
		(fp_line
			(start -0.12065 0.2794)
			(end -0.12065 0.3048)
			(stroke
				(width 0.1)
				(type default)
			)
			(layer "F.Fab")
		)
		(fp_line
			(start -0.12065 -0.2794)
			(end 0.12065 -0.2794)
			(stroke
				(width 0.1)
				(type default)
			)
			(layer "F.Fab")
		)
		(fp_line
			(start -0.12065 -0.305054)
			(end -0.12065 -0.2794)
			(stroke
				(width 0.1)
				(type default)
			)
			(layer "F.Fab")
		)
		(fp_line
			(start -0.67945 0.3048)
			(end -0.67945 -0.305054)
			(stroke
				(width 0.1)
				(type default)
			)
			(layer "F.Fab")
		)
		(fp_line
			(start -0.67945 -0.305054)
			(end -0.12065 -0.305054)
			(stroke
				(width 0.1)
				(type default)
			)
			(layer "F.Fab")
		)
		(pad "1" smd circle
			(at -0.40005 0 180)
			(size 0 0)
			(layers "F.Cu" "F.Mask" "F.Paste")
			(net "P3V3_E1S_0_R")
		)
		(pad "2" smd circle
			(at 0.40005 0 180)
			(size 0 0)
			(layers "F.Cu" "F.Mask" "F.Paste")
			(net "VSENSE_P3V3_INA230_2_INP")
		)
	)
	(footprint ""
		(layer "F.Cu")
		(at 21.81987 -385.91109 180)
		(property "Reference" "PC6641"
			(at 0 0 180)
			(layer "F.SilkS")
			(hide yes)
			(effects
				(font
					(size 1.27 1.27)
				)
			)
		)
		(property "Value" ""
			(at 0 0 180)
			(layer "F.Fab")
			(effects
				(font
					(size 1.27 1.27)
				)
			)
		)
		(duplicate_pad_numbers_are_jumpers no)
		(fp_line
			(start 0.7874 0.4064)
			(end -0.7874 0.4064)
			(stroke
				(width 0.1524)
				(type default)
			)
			(layer "F.SilkS")
		)
		(fp_line
			(start 0.7874 -0.4064)
			(end 0.7874 0.4064)
			(stroke
				(width 0.1524)
				(type default)
			)
			(layer "F.SilkS")
		)
		(fp_line
			(start -0.7874 0.4064)
			(end -0.7874 -0.4064)
			(stroke
				(width 0.1524)
				(type default)
			)
			(layer "F.SilkS")
		)
		(fp_line
			(start -0.7874 -0.4064)
			(end 0.7874 -0.4064)
			(stroke
				(width 0.1524)
				(type default)
			)
			(layer "F.SilkS")
		)
		(fp_line
			(start 0.67945 0.3048)
			(end 0.120396 0.3048)
			(stroke
				(width 0.1)
				(type default)
			)
			(layer "F.Fab")
		)
		(fp_line
			(start 0.67945 -0.3048)
			(end 0.67945 0.3048)
			(stroke
				(width 0.1)
				(type default)
			)
			(layer "F.Fab")
		)
		(fp_line
			(start 0.12065 -0.2794)
			(end 0.12065 -0.3048)
			(stroke
				(width 0.1)
				(type default)
			)
			(layer "F.Fab")
		)
		(fp_line
			(start 0.12065 -0.3048)
			(end 0.67945 -0.3048)
			(stroke
				(width 0.1)
				(type default)
			)
			(layer "F.Fab")
		)
		(fp_line
			(start 0.120396 0.3048)
			(end 0.120396 0.2794)
			(stroke
				(width 0.1)
				(type default)
			)
			(layer "F.Fab")
		)
		(fp_line
			(start 0.120396 0.2794)
			(end -0.12065 0.2794)
			(stroke
				(width 0.1)
				(type default)
			)
			(layer "F.Fab")
		)
		(fp_line
			(start -0.12065 0.3048)
			(end -0.67945 0.3048)
			(stroke
				(width 0.1)
				(type default)
			)
			(layer "F.Fab")
		)
		(fp_line
			(start -0.12065 0.2794)
			(end -0.12065 0.3048)
			(stroke
				(width 0.1)
				(type default)
			)
			(layer "F.Fab")
		)
		(fp_line
			(start -0.12065 -0.2794)
			(end 0.12065 -0.2794)
			(stroke
				(width 0.1)
				(type default)
			)
			(layer "F.Fab")
		)
		(fp_line
			(start -0.12065 -0.305054)
			(end -0.12065 -0.2794)
			(stroke
				(width 0.1)
				(type default)
			)
			(layer "F.Fab")
		)
		(fp_line
			(start -0.67945 0.3048)
			(end -0.67945 -0.305054)
			(stroke
				(width 0.1)
				(type default)
			)
			(layer "F.Fab")
		)
		(fp_line
			(start -0.67945 -0.305054)
			(end -0.12065 -0.305054)
			(stroke
				(width 0.1)
				(type default)
			)
			(layer "F.Fab")
		)
		(pad "1" smd circle
			(at -0.40005 0 180)
			(size 0 0)
			(layers "F.Cu" "F.Mask" "F.Paste")
			(net "SW_P0V9_RETIMER_CPU1_SW2")
		)
		(pad "2" smd circle
			(at 0.40005 0 180)
			(size 0 0)
			(layers "F.Cu" "F.Mask" "F.Paste")
			(net "SW_P0V9_RETIMER_CPU1_SW2_RC")
		)
	)
)
